(kicad_pcb
	(version 20260206)
	(generator "pcbnew")
	(generator_version "10.0")
	(general
		(thickness 1.6)
		(legacy_teardrops no)
	)
	(paper "A4")
	(title_block
		(title "01162023_DA0F0TEBIF0_F0T_Expander_BD_F_brd_V02_OCP.brd")
		(comment 1 "Grand Teton / footprints 1564-1568 of 9728")
	)
	(layers
		(0 "F.Cu" signal "TOP")
		(4 "In1.Cu" signal "GND")
		(6 "In2.Cu" signal "VCC")
		(8 "In3.Cu" signal "VCC1")
		(10 "In4.Cu" signal "GND1")
		(12 "In5.Cu" signal "IN1")
		(14 "In6.Cu" signal "GND2")
		(16 "In7.Cu" signal "IN2")
		(18 "In8.Cu" signal "GND3")
		(20 "In9.Cu" signal "IN3")
		(22 "In10.Cu" signal "GND4")
		(24 "In11.Cu" signal "IN4")
		(26 "In12.Cu" signal "GND5")
		(28 "In13.Cu" signal "IN5")
		(30 "In14.Cu" signal "GND6")
		(32 "In15.Cu" signal "IN6")
		(34 "In16.Cu" signal "GND7")
		(2 "B.Cu" signal "BOTTOM")
		(9 "F.Adhes" user "F.Adhesive")
		(11 "B.Adhes" user "B.Adhesive")
		(13 "F.Paste" user "Package Geometry/Pastemask Top")
		(15 "B.Paste" user "Package Geometry/Pastemask Bottom")
		(5 "F.SilkS" user "Ref Des/Silkscreen Top")
		(7 "B.SilkS" user "Ref Des/Silkscreen Bottom")
		(1 "F.Mask" user "Board Geometry/Soldermask Top")
		(3 "B.Mask" user "Board Geometry/Soldermask Bottom")
		(17 "Dwgs.User" user "User.Drawings")
		(19 "Cmts.User" user "User.Comments")
		(21 "Eco1.User" user "User.Eco1")
		(23 "Eco2.User" user "User.Eco2")
		(25 "Edge.Cuts" user "Board Geometry/Outline")
		(27 "Margin" user)
		(31 "F.CrtYd" user "Package Geometry/Place Bound Top")
		(29 "B.CrtYd" user "Package Geometry/Place Bound Bottom")
		(35 "F.Fab" user "Ref Des/Assembly Top")
		(33 "B.Fab" user "Ref Des/Assembly Bottom")
	)
	(footprint ""
		(layer "F.Cu")
		(at 355.19106 -55.663846 90)
		(property "Reference" "PU63"
			(at -0.900176 2.939034 90)
			(unlocked yes)
			(layer "F.SilkS")
			(effects
				(font
					(size 0.7874 0.5842)
					(thickness 0.1524)
				)
				(justify left)
			)
		)
		(property "Value" ""
			(at 0 0 90)
			(layer "F.Fab")
			(effects
				(font
					(size 1.27 1.27)
				)
			)
		)
		(duplicate_pad_numbers_are_jumpers no)
		(fp_line
			(start 1.943608 -1.549908)
			(end 1.943608 1.549908)
			(stroke
				(width 0.1524)
				(type default)
			)
			(layer "F.SilkS")
		)
		(fp_line
			(start -1.943608 -1.549908)
			(end 1.943608 -1.549908)
			(stroke
				(width 0.1524)
				(type default)
			)
			(layer "F.SilkS")
		)
		(fp_line
			(start 1.943608 1.549908)
			(end -1.943608 1.549908)
			(stroke
				(width 0.1524)
				(type default)
			)
			(layer "F.SilkS")
		)
		(fp_line
			(start -1.943608 1.549908)
			(end -1.943608 -1.549908)
			(stroke
				(width 0.1524)
				(type default)
			)
			(layer "F.SilkS")
		)
		(fp_poly
			(pts
				(xy -2.019808 -1.549908) (xy -1.257808 -1.549908) (xy -1.257808 -1.880108) (xy -2.019808 -1.880108)
			)
			(stroke
				(width 0)
				(type default)
			)
			(fill yes)
			(layer "F.SilkS")
		)
		(fp_line
			(start 1.549908 -1.549908)
			(end 1.549908 1.549908)
			(stroke
				(width 0.1)
				(type default)
			)
			(layer "F.Fab")
		)
		(fp_line
			(start -1.549908 -1.549908)
			(end 1.549908 -1.549908)
			(stroke
				(width 0.1)
				(type default)
			)
			(layer "F.Fab")
		)
		(fp_line
			(start 1.549908 1.549908)
			(end -1.549908 1.549908)
			(stroke
				(width 0.1)
				(type default)
			)
			(layer "F.Fab")
		)
		(fp_line
			(start -1.549908 1.549908)
			(end -1.549908 -1.549908)
			(stroke
				(width 0.1)
				(type default)
			)
			(layer "F.Fab")
		)
		(fp_poly
			(pts
				(xy -2.019808 -1.549908) (xy -1.257808 -1.549908) (xy -1.257808 -1.880108) (xy -2.019808 -1.880108)
			)
			(stroke
				(width 0)
				(type default)
			)
			(fill yes)
			(layer "F.Fab")
		)
		(pad "1" smd rect
			(at -1.500124 -1.249934)
			(size 0.2794 0.6096)
			(layers "F.Cu" "F.Mask" "F.Paste")
			(net "P3V3_SSD12")
		)
		(pad "2" smd rect
			(at -1.500124 -0.750062)
			(size 0.2794 0.6096)
			(layers "F.Cu" "F.Mask" "F.Paste")
			(net "P3V3_SSD12")
		)
		(pad "3" smd rect
			(at -1.500124 -0.249936)
			(size 0.2794 0.6096)
			(layers "F.Cu" "F.Mask" "F.Paste")
			(net "P3V3_SSD12")
		)
		(pad "4" smd rect
			(at -1.500124 0.249936)
			(size 0.2794 0.6096)
			(layers "F.Cu" "F.Mask" "F.Paste")
			(net "P3V3_SSD12")
		)
		(pad "5" smd rect
			(at -1.500124 0.750062)
			(size 0.2794 0.6096)
			(layers "F.Cu" "F.Mask" "F.Paste")
			(net "P3V3_SSD12")
		)
		(pad "6" smd rect
			(at -1.500124 1.249934)
			(size 0.2794 0.6096)
			(layers "F.Cu" "F.Mask" "F.Paste")
			(net "GND")
		)
		(pad "7" smd rect
			(at 1.500124 1.249934)
			(size 0.2794 0.6096)
			(layers "F.Cu" "F.Mask" "F.Paste")
			(net "P3V3_SSD12_SS")
		)
		(pad "8" smd rect
			(at 1.500124 0.750062)
			(size 0.2794 0.6096)
			(layers "F.Cu" "F.Mask" "F.Paste")
			(net "PWRGD_P3V3_SSD12")
		)
		(pad "9" smd rect
			(at 1.500124 0.249936)
			(size 0.2794 0.6096)
			(layers "F.Cu" "F.Mask" "F.Paste")
			(net "P3V3_SSD12_OCP")
		)
		(pad "10" smd rect
			(at 1.500124 -0.249936)
			(size 0.2794 0.6096)
			(layers "F.Cu" "F.Mask" "F.Paste")
			(net "P5V_AUX")
		)
		(pad "11" smd rect
			(at 1.500124 -0.750062)
			(size 0.2794 0.6096)
			(layers "F.Cu" "F.Mask" "F.Paste")
			(net "SSD12_AUX_P3V3_EN_R")
		)
		(pad "12" smd rect
			(at 1.500124 -1.249934)
			(size 0.2794 0.6096)
			(layers "F.Cu" "F.Mask" "F.Paste")
			(net "P3V3_AUX")
		)
		(pad "13" smd rect
			(at 0 0 90)
			(size 1.9812 2.7178)
			(layers "F.Cu" "F.Mask" "F.Paste")
			(net "P3V3_AUX")
		)
		(zone
			(layer "F.Cu")
			(hatch none 0.5)
			(connect_pads
				(clearance 0)
			)
			(min_thickness 0.25)
			(keepout
				(tracks not_allowed)
				(vias allowed)
				(pads allowed)
				(copperpour not_allowed)
				(footprints allowed)
			)
			(placement
				(enabled no)
				(sheetname "")
			)
			(fill
				(thermal_gap 0.5)
				(thermal_bridge_width 0.5)
				(island_removal_mode 0)
			)
			(polygon
				(pts
					(xy 353.64166 -56.806846) (xy 353.76866 -56.806846) (xy 356.74046 -56.806846) (xy 356.740968 -56.806846)
					(xy 356.740968 -54.520846) (xy 356.74046 -54.520846) (xy 356.61346 -54.520846) (xy 355.19106 -54.520846)
					(xy 355.19106 -54.622446) (xy 356.61346 -54.622446) (xy 356.61346 -56.705246) (xy 353.76866 -56.705246)
					(xy 353.76866 -54.622446) (xy 355.16566 -54.622446) (xy 355.16566 -54.520846) (xy 353.76866 -54.520846)
					(xy 353.64166 -54.520846) (xy 353.641152 -54.520846) (xy 353.641152 -56.806846)
				)
			)
		)
	)
	(footprint ""
		(layer "F.Cu")
		(at 254.085598 -25.1587 -90)
		(property "Reference" "R5760"
			(at 0 0 270)
			(layer "F.SilkS")
			(hide yes)
			(effects
				(font
					(size 1.27 1.27)
				)
			)
		)
		(property "Value" ""
			(at 0 0 270)
			(layer "F.Fab")
			(effects
				(font
					(size 1.27 1.27)
				)
			)
		)
		(duplicate_pad_numbers_are_jumpers no)
		(fp_line
			(start -0.7874 0.4064)
			(end -0.7874 -0.4064)
			(stroke
				(width 0.1524)
				(type default)
			)
			(layer "F.SilkS")
		)
		(fp_line
			(start 0.7874 0.4064)
			(end -0.7874 0.4064)
			(stroke
				(width 0.1524)
				(type default)
			)
			(layer "F.SilkS")
		)
		(fp_line
			(start -0.7874 -0.4064)
			(end 0.7874 -0.4064)
			(stroke
				(width 0.1524)
				(type default)
			)
			(layer "F.SilkS")
		)
		(fp_line
			(start 0.7874 -0.4064)
			(end 0.7874 0.4064)
			(stroke
				(width 0.1524)
				(type default)
			)
			(layer "F.SilkS")
		)
		(fp_line
			(start -0.67945 0.3048)
			(end -0.67945 -0.305054)
			(stroke
				(width 0.1)
				(type default)
			)
			(layer "F.Fab")
		)
		(fp_line
			(start -0.12065 0.3048)
			(end -0.67945 0.3048)
			(stroke
				(width 0.1)
				(type default)
			)
			(layer "F.Fab")
		)
		(fp_line
			(start 0.120396 0.3048)
			(end 0.120396 0.2794)
			(stroke
				(width 0.1)
				(type default)
			)
			(layer "F.Fab")
		)
		(fp_line
			(start 0.67945 0.3048)
			(end 0.120396 0.3048)
			(stroke
				(width 0.1)
				(type default)
			)
			(layer "F.Fab")
		)
		(fp_line
			(start -0.12065 0.2794)
			(end -0.12065 0.3048)
			(stroke
				(width 0.1)
				(type default)
			)
			(layer "F.Fab")
		)
		(fp_line
			(start 0.120396 0.2794)
			(end -0.12065 0.2794)
			(stroke
				(width 0.1)
				(type default)
			)
			(layer "F.Fab")
		)
		(fp_line
			(start -0.12065 -0.2794)
			(end 0.12065 -0.2794)
			(stroke
				(width 0.1)
				(type default)
			)
			(layer "F.Fab")
		)
		(fp_line
			(start 0.12065 -0.2794)
			(end 0.12065 -0.3048)
			(stroke
				(width 0.1)
				(type default)
			)
			(layer "F.Fab")
		)
		(fp_line
			(start 0.12065 -0.3048)
			(end 0.67945 -0.3048)
			(stroke
				(width 0.1)
				(type default)
			)
			(layer "F.Fab")
		)
		(fp_line
			(start 0.67945 -0.3048)
			(end 0.67945 0.3048)
			(stroke
				(width 0.1)
				(type default)
			)
			(layer "F.Fab")
		)
		(fp_line
			(start -0.67945 -0.305054)
			(end -0.12065 -0.305054)
			(stroke
				(width 0.1)
				(type default)
			)
			(layer "F.Fab")
		)
		(fp_line
			(start -0.12065 -0.305054)
			(end -0.12065 -0.2794)
			(stroke
				(width 0.1)
				(type default)
			)
			(layer "F.Fab")
		)
		(pad "1" smd circle
			(at -0.40005 0 270)
			(size 0 0)
			(layers "F.Cu" "F.Mask" "F.Paste")
			(net "SSD8_LED_ISO_N")
		)
		(pad "2" smd circle
			(at 0.40005 0 270)
			(size 0 0)
			(layers "F.Cu" "F.Mask" "F.Paste")
			(net "SSD8_LED_ISO_R_N")
		)
	)
	(footprint ""
		(layer "F.Cu")
		(at 322.239386 -96.811592 -90)
		(property "Reference" "R739"
			(at 0 0 270)
			(layer "F.SilkS")
			(hide yes)
			(effects
				(font
					(size 1.27 1.27)
				)
			)
		)
		(property "Value" ""
			(at 0 0 270)
			(layer "F.Fab")
			(effects
				(font
					(size 1.27 1.27)
				)
			)
		)
		(duplicate_pad_numbers_are_jumpers no)
		(fp_line
			(start -0.7874 0.4064)
			(end -0.7874 -0.4064)
			(stroke
				(width 0.1524)
				(type default)
			)
			(layer "F.SilkS")
		)
		(fp_line
			(start 0.7874 0.4064)
			(end -0.7874 0.4064)
			(stroke
				(width 0.1524)
				(type default)
			)
			(layer "F.SilkS")
		)
		(fp_line
			(start -0.7874 -0.4064)
			(end 0.7874 -0.4064)
			(stroke
				(width 0.1524)
				(type default)
			)
			(layer "F.SilkS")
		)
		(fp_line
			(start 0.7874 -0.4064)
			(end 0.7874 0.4064)
			(stroke
				(width 0.1524)
				(type default)
			)
			(layer "F.SilkS")
		)
		(fp_line
			(start -0.67945 0.3048)
			(end -0.67945 -0.305054)
			(stroke
				(width 0.1)
				(type default)
			)
			(layer "F.Fab")
		)
		(fp_line
			(start -0.12065 0.3048)
			(end -0.67945 0.3048)
			(stroke
				(width 0.1)
				(type default)
			)
			(layer "F.Fab")
		)
		(fp_line
			(start 0.120396 0.3048)
			(end 0.120396 0.2794)
			(stroke
				(width 0.1)
				(type default)
			)
			(layer "F.Fab")
		)
		(fp_line
			(start 0.67945 0.3048)
			(end 0.120396 0.3048)
			(stroke
				(width 0.1)
				(type default)
			)
			(layer "F.Fab")
		)
		(fp_line
			(start -0.12065 0.2794)
			(end -0.12065 0.3048)
			(stroke
				(width 0.1)
				(type default)
			)
			(layer "F.Fab")
		)
		(fp_line
			(start 0.120396 0.2794)
			(end -0.12065 0.2794)
			(stroke
				(width 0.1)
				(type default)
			)
			(layer "F.Fab")
		)
		(fp_line
			(start -0.12065 -0.2794)
			(end 0.12065 -0.2794)
			(stroke
				(width 0.1)
				(type default)
			)
			(layer "F.Fab")
		)
		(fp_line
			(start 0.12065 -0.2794)
			(end 0.12065 -0.3048)
			(stroke
				(width 0.1)
				(type default)
			)
			(layer "F.Fab")
		)
		(fp_line
			(start 0.12065 -0.3048)
			(end 0.67945 -0.3048)
			(stroke
				(width 0.1)
				(type default)
			)
			(layer "F.Fab")
		)
		(fp_line
			(start 0.67945 -0.3048)
			(end 0.67945 0.3048)
			(stroke
				(width 0.1)
				(type default)
			)
			(layer "F.Fab")
		)
		(fp_line
			(start -0.67945 -0.305054)
			(end -0.12065 -0.305054)
			(stroke
				(width 0.1)
				(type default)
			)
			(layer "F.Fab")
		)
		(fp_line
			(start -0.12065 -0.305054)
			(end -0.12065 -0.2794)
			(stroke
				(width 0.1)
				(type default)
			)
			(layer "F.Fab")
		)
		(pad "1" smd circle
			(at -0.40005 0 270)
			(size 0 0)
			(layers "F.Cu" "F.Mask" "F.Paste")
			(net "NIC5_ADC_A0")
		)
		(pad "2" smd circle
			(at 0.40005 0 270)
			(size 0 0)
			(layers "F.Cu" "F.Mask" "F.Paste")
			(net "GND")
		)
	)
	(footprint ""
		(layer "F.Cu")
		(at 458.18679 -365.54156 -90)
		(property "Reference" "R6689"
			(at 0 0 270)
			(layer "F.SilkS")
			(hide yes)
			(effects
				(font
					(size 1.27 1.27)
				)
			)
		)
		(property "Value" ""
			(at 0 0 270)
			(layer "F.Fab")
			(effects
				(font
					(size 1.27 1.27)
				)
			)
		)
		(duplicate_pad_numbers_are_jumpers no)
		(fp_line
			(start -0.7874 0.4064)
			(end -0.7874 -0.4064)
			(stroke
				(width 0.1524)
				(type default)
			)
			(layer "F.SilkS")
		)
		(fp_line
			(start 0.7874 0.4064)
			(end -0.7874 0.4064)
			(stroke
				(width 0.1524)
				(type default)
			)
			(layer "F.SilkS")
		)
		(fp_line
			(start -0.7874 -0.4064)
			(end 0.7874 -0.4064)
			(stroke
				(width 0.1524)
				(type default)
			)
			(layer "F.SilkS")
		)
		(fp_line
			(start 0.7874 -0.4064)
			(end 0.7874 0.4064)
			(stroke
				(width 0.1524)
				(type default)
			)
			(layer "F.SilkS")
		)
		(fp_line
			(start -0.67945 0.3048)
			(end -0.67945 -0.305054)
			(stroke
				(width 0.1)
				(type default)
			)
			(layer "F.Fab")
		)
		(fp_line
			(start -0.12065 0.3048)
			(end -0.67945 0.3048)
			(stroke
				(width 0.1)
				(type default)
			)
			(layer "F.Fab")
		)
		(fp_line
			(start 0.120396 0.3048)
			(end 0.120396 0.2794)
			(stroke
				(width 0.1)
				(type default)
			)
			(layer "F.Fab")
		)
		(fp_line
			(start 0.67945 0.3048)
			(end 0.120396 0.3048)
			(stroke
				(width 0.1)
				(type default)
			)
			(layer "F.Fab")
		)
		(fp_line
			(start -0.12065 0.2794)
			(end -0.12065 0.3048)
			(stroke
				(width 0.1)
				(type default)
			)
			(layer "F.Fab")
		)
		(fp_line
			(start 0.120396 0.2794)
			(end -0.12065 0.2794)
			(stroke
				(width 0.1)
				(type default)
			)
			(layer "F.Fab")
		)
		(fp_line
			(start -0.12065 -0.2794)
			(end 0.12065 -0.2794)
			(stroke
				(width 0.1)
				(type default)
			)
			(layer "F.Fab")
		)
		(fp_line
			(start 0.12065 -0.2794)
			(end 0.12065 -0.3048)
			(stroke
				(width 0.1)
				(type default)
			)
			(layer "F.Fab")
		)
		(fp_line
			(start 0.12065 -0.3048)
			(end 0.67945 -0.3048)
			(stroke
				(width 0.1)
				(type default)
			)
			(layer "F.Fab")
		)
		(fp_line
			(start 0.67945 -0.3048)
			(end 0.67945 0.3048)
			(stroke
				(width 0.1)
				(type default)
			)
			(layer "F.Fab")
		)
		(fp_line
			(start -0.67945 -0.305054)
			(end -0.12065 -0.305054)
			(stroke
				(width 0.1)
				(type default)
			)
			(layer "F.Fab")
		)
		(fp_line
			(start -0.12065 -0.305054)
			(end -0.12065 -0.2794)
			(stroke
				(width 0.1)
				(type default)
			)
			(layer "F.Fab")
		)
		(pad "1" smd circle
			(at -0.40005 0 270)
			(size 0 0)
			(layers "F.Cu" "F.Mask" "F.Paste")
			(net "GPU_3V3IO_RSVD4_ISO")
		)
		(pad "2" smd circle
			(at 0.40005 0 270)
			(size 0 0)
			(layers "F.Cu" "F.Mask" "F.Paste")
			(net "P3V3_AUX")
		)
	)
	(footprint ""
		(layer "F.Cu")
		(at 436.07736 -309.791354 135)
		(property "Reference" "R1446"
			(at 0 0 135)
			(layer "F.SilkS")
			(hide yes)
			(effects
				(font
					(size 1.27 1.27)
				)
			)
		)
		(property "Value" ""
			(at 0 0 135)
			(layer "F.Fab")
			(effects
				(font
					(size 1.27 1.27)
				)
			)
		)
		(duplicate_pad_numbers_are_jumpers no)
		(fp_line
			(start 0.787389 -0.406267)
			(end 0.787389 0.406267)
			(stroke
				(width 0.1524)
				(type default)
			)
			(layer "F.SilkS")
		)
		(fp_line
			(start 0.787389 0.406267)
			(end -0.787389 0.406267)
			(stroke
				(width 0.1524)
				(type default)
			)
			(layer "F.SilkS")
		)
		(fp_line
			(start -0.787389 -0.406267)
			(end 0.787389 -0.406267)
			(stroke
				(width 0.1524)
				(type default)
			)
			(layer "F.SilkS")
		)
		(fp_line
			(start -0.787389 0.406267)
			(end -0.787389 -0.406267)
			(stroke
				(width 0.1524)
				(type default)
			)
			(layer "F.SilkS")
		)
		(fp_line
			(start 0.679446 -0.30479)
			(end 0.679446 0.30479)
			(stroke
				(width 0.1)
				(type default)
			)
			(layer "F.Fab")
		)
		(fp_line
			(start 0.120515 -0.30479)
			(end 0.679446 -0.30479)
			(stroke
				(width 0.1)
				(type default)
			)
			(layer "F.Fab")
		)
		(fp_line
			(start 0.120695 -0.279466)
			(end 0.120515 -0.30479)
			(stroke
				(width 0.1)
				(type default)
			)
			(layer "F.Fab")
		)
		(fp_line
			(start 0.679446 0.30479)
			(end 0.120515 0.30479)
			(stroke
				(width 0.1)
				(type default)
			)
			(layer "F.Fab")
		)
		(fp_line
			(start -0.120695 -0.304969)
			(end -0.120695 -0.279466)
			(stroke
				(width 0.1)
				(type default)
			)
			(layer "F.Fab")
		)
		(fp_line
			(start -0.120695 -0.279466)
			(end 0.120695 -0.279466)
			(stroke
				(width 0.1)
				(type default)
			)
			(layer "F.Fab")
		)
		(fp_line
			(start 0.120335 0.279466)
			(end -0.120695 0.279466)
			(stroke
				(width 0.1)
				(type default)
			)
			(layer "F.Fab")
		)
		(fp_line
			(start 0.120515 0.30479)
			(end 0.120335 0.279466)
			(stroke
				(width 0.1)
				(type default)
			)
			(layer "F.Fab")
		)
		(fp_line
			(start -0.679446 -0.305149)
			(end -0.120695 -0.304969)
			(stroke
				(width 0.1)
				(type default)
			)
			(layer "F.Fab")
		)
		(fp_line
			(start -0.120695 0.279466)
			(end -0.120515 0.30479)
			(stroke
				(width 0.1)
				(type default)
			)
			(layer "F.Fab")
		)
		(fp_line
			(start -0.120515 0.30479)
			(end -0.679446 0.30479)
			(stroke
				(width 0.1)
				(type default)
			)
			(layer "F.Fab")
		)
		(fp_line
			(start -0.679446 0.30479)
			(end -0.679446 -0.305149)
			(stroke
				(width 0.1)
				(type default)
			)
			(layer "F.Fab")
		)
		(pad "1" smd circle
			(at -0.40005 0 135)
			(size 0 0)
			(layers "F.Cu" "F.Mask" "F.Paste")
			(net "PEX3_SPARE7")
		)
		(pad "2" smd circle
			(at 0.40005 0 135)
			(size 0 0)
			(layers "F.Cu" "F.Mask" "F.Paste")
			(net "P1V8_PEX")
		)
	)
)
